(kicad_pcb
	(version 20241229)
	(generator "pcbnew")
	(generator_version "9.0")
	(general
		(thickness 1.6)
		(legacy_teardrops no)
	)
	(paper "A4")
	(title_block
		(title "GMSL Deserializer")
		(date "2025-10-09")
		(rev "1.0.4")
		(company "Antmicro Ltd")
		(comment 1 "www.antmicro.com")
		(comment 9 "footprints 49-55 of 235")
	)
	(layers
		(0 "F.Cu" signal)
		(4 "In1.Cu" power)
		(6 "In2.Cu" power)
		(2 "B.Cu" signal)
		(9 "F.Adhes" user "F.Adhesive")
		(11 "B.Adhes" user "B.Adhesive")
		(13 "F.Paste" user)
		(15 "B.Paste" user)
		(5 "F.SilkS" user "F.Silkscreen")
		(7 "B.SilkS" user "B.Silkscreen")
		(1 "F.Mask" user)
		(3 "B.Mask" user)
		(17 "Dwgs.User" user "User.Drawings")
		(19 "Cmts.User" user "User.Comments")
		(21 "Eco1.User" user "User.Eco1")
		(23 "Eco2.User" user "User.Eco2")
		(25 "Edge.Cuts" user)
		(27 "Margin" user)
		(31 "F.CrtYd" user "F.Courtyard")
		(29 "B.CrtYd" user "B.Courtyard")
		(35 "F.Fab" user)
		(33 "B.Fab" user)
	)
	(footprint "antmicro-footprints:R_0402_1005Metric"
		(layer "F.Cu")
		(at 119.149 84.328)
		(descr "Resistor SMD 0402")
		(tags "resistor SMD 0402")
		(property "Reference" "R65"
			(at -3.325 0.508 0)
			(layer "F.SilkS")
			(effects
				(font
					(size 0.7 0.7)
					(thickness 0.15)
				)
				(justify left bottom)
			)
		)
		(property "Value" "R_10k_0402"
			(at -1.011843 1.772047 0)
			(layer "F.Fab")
			(effects
				(font
					(size 0.7 0.7)
					(thickness 0.15)
				)
				(justify left bottom)
			)
		)
		(property "Datasheet" "https://www.bourns.com/docs/product-datasheets/cr.pdf"
			(at 0 0 0)
			(layer "F.Fab")
			(hide yes)
			(effects
				(font
					(size 1.27 1.27)
					(thickness 0.15)
				)
			)
		)
		(property "Description" "SMD Chip Resistor, 10 kohm, ± 1%, 62.5 mW, 0402 [1005 Metric], Thick Film, General Purpose"
			(at 0 0 0)
			(layer "F.Fab")
			(hide yes)
			(effects
				(font
					(size 1.27 1.27)
					(thickness 0.15)
				)
			)
		)
		(property "Author" "Antmicro"
			(at 0 0 0)
			(layer "F.Fab")
			(hide yes)
			(effects
				(font
					(size 1 1)
					(thickness 0.15)
				)
			)
		)
		(property "License" "Apache-2.0"
			(at 0 0 0)
			(layer "F.Fab")
			(hide yes)
			(effects
				(font
					(size 1 1)
					(thickness 0.15)
				)
			)
		)
		(property "MPN" "CR0402-FX-1002GLF"
			(at 0 0 0)
			(layer "F.Fab")
			(hide yes)
			(effects
				(font
					(size 1 1)
					(thickness 0.15)
				)
			)
		)
		(property "Manufacturer" "Bourns"
			(at 0 0 0)
			(layer "F.Fab")
			(hide yes)
			(effects
				(font
					(size 1 1)
					(thickness 0.15)
				)
			)
		)
		(property "Tolerance" "1%"
			(at 0 0 0)
			(layer "F.Fab")
			(hide yes)
			(effects
				(font
					(size 1 1)
					(thickness 0.15)
				)
			)
		)
		(property "Val" "10k"
			(at 0 0 0)
			(layer "F.Fab")
			(hide yes)
			(effects
				(font
					(size 1 1)
					(thickness 0.15)
				)
			)
		)
		(sheetname "/Power/")
		(sheetfile "power.kicad_sch")
		(attr smd)
		(fp_rect
			(start -0.925 -0.47)
			(end 0.925 0.47)
			(stroke
				(width 0.05)
				(type default)
			)
			(fill no)
			(layer "F.CrtYd")
		)
		(fp_rect
			(start -0.5 -0.25)
			(end 0.5 0.25)
			(stroke
				(width 0.15)
				(type solid)
			)
			(fill no)
			(layer "F.Fab")
		)
		(pad "1" smd roundrect
			(at -0.48 0)
			(size 0.59 0.64)
			(layers "F.Cu" "F.Mask" "F.Paste")
			(roundrect_rratio 0.25)
			(net 1 "GND")
			(pintype "passive")
		)
		(pad "2" smd roundrect
			(at 0.48 0)
			(size 0.59 0.64)
			(layers "F.Cu" "F.Mask" "F.Paste")
			(roundrect_rratio 0.25)
			(net 68 "/Power/EN_1V2")
			(pintype "passive")
		)
	)
	(footprint "antmicro-footprints:TP_SMD_0.75mm"
		(layer "F.Cu")
		(at 146.812 74.422)
		(property "Reference" "TP2"
			(at -2.99467 1.167469 0)
			(layer "F.SilkS")
			(hide yes)
			(effects
				(font
					(size 0.7 0.7)
					(thickness 0.15)
				)
				(justify left bottom)
			)
		)
		(property "Value" "TP_0.75mm_SMD"
			(at 0 1.2 0)
			(layer "F.Fab")
			(effects
				(font
					(size 0.7 0.7)
					(thickness 0.15)
				)
				(justify left bottom)
			)
		)
		(property "Description" "SMT test point"
			(at 0 0 0)
			(layer "F.Fab")
			(hide yes)
			(effects
				(font
					(size 1.27 1.27)
					(thickness 0.15)
				)
			)
		)
		(property "Author" "Antmicro"
			(at 0 0 0)
			(layer "F.Fab")
			(hide yes)
			(effects
				(font
					(size 1 1)
					(thickness 0.15)
				)
			)
		)
		(property "License" "Apache-2.0"
			(at 0 0 0)
			(layer "F.Fab")
			(hide yes)
			(effects
				(font
					(size 1 1)
					(thickness 0.15)
				)
			)
		)
		(property "MPN" ""
			(at 0 0 0)
			(layer "F.Fab")
			(hide yes)
			(effects
				(font
					(size 1 1)
					(thickness 0.15)
				)
			)
		)
		(property "Manufacturer" ""
			(at 0 0 0)
			(layer "F.Fab")
			(hide yes)
			(effects
				(font
					(size 1 1)
					(thickness 0.15)
				)
			)
		)
		(sheetname "/Connectors/")
		(sheetfile "connectors.kicad_sch")
		(fp_circle
			(center 0 0)
			(end 0.475 0)
			(stroke
				(width 0.05)
				(type default)
			)
			(fill no)
			(layer "F.CrtYd")
		)
		(pad "1" smd circle
			(at 0 0)
			(size 0.75 0.75)
			(layers "F.Cu" "F.Mask")
			(net 85 "/Connectors/MFP5")
			(pinfunction "1")
			(pintype "passive")
		)
	)
	(footprint "antmicro-footprints:C_0402_1005Metric"
		(layer "F.Cu")
		(at 146.994 66.5485 90)
		(descr "Capacitor SMD 0402")
		(tags "capacitor SMD 0402")
		(property "Reference" "C8"
			(at -1.3965 1.215 90)
			(layer "F.SilkS")
			(effects
				(font
					(size 0.7 0.7)
					(thickness 0.15)
				)
				(justify left bottom)
			)
		)
		(property "Value" "C_100n_0402"
			(at -1.022927 2.155213 90)
			(layer "F.Fab")
			(effects
				(font
					(size 0.7 0.7)
					(thickness 0.15)
				)
				(justify left bottom)
			)
		)
		(property "Datasheet" "https://www.murata.com/products/productdetail?partno=GRM155R61H104KE14%23"
			(at 0 0 90)
			(layer "F.Fab")
			(hide yes)
			(effects
				(font
					(size 1.27 1.27)
					(thickness 0.15)
				)
			)
		)
		(property "Description" "SMD Multilayer Ceramic Capacitor, 0.1 µF, 50 V, 0402 [1005 Metric], ± 10%, X5R, GRM Series"
			(at 0 0 90)
			(layer "F.Fab")
			(hide yes)
			(effects
				(font
					(size 1.27 1.27)
					(thickness 0.15)
				)
			)
		)
		(property "Author" "Antmicro"
			(at 213.5425 -80.4455 0)
			(layer "F.Fab")
			(hide yes)
			(effects
				(font
					(size 1 1)
					(thickness 0.15)
				)
			)
		)
		(property "Dielectric" "X5R"
			(at 213.5425 -80.4455 0)
			(layer "F.Fab")
			(hide yes)
			(effects
				(font
					(size 1 1)
					(thickness 0.15)
				)
			)
		)
		(property "License" "Apache-2.0"
			(at 213.5425 -80.4455 0)
			(layer "F.Fab")
			(hide yes)
			(effects
				(font
					(size 1 1)
					(thickness 0.15)
				)
			)
		)
		(property "MPN" "GRM155R61H104KE14D"
			(at 213.5425 -80.4455 0)
			(layer "F.Fab")
			(hide yes)
			(effects
				(font
					(size 1 1)
					(thickness 0.15)
				)
			)
		)
		(property "Manufacturer" "Murata"
			(at 213.5425 -80.4455 0)
			(layer "F.Fab")
			(hide yes)
			(effects
				(font
					(size 1 1)
					(thickness 0.15)
				)
			)
		)
		(property "Val" "100n"
			(at 213.5425 -80.4455 0)
			(layer "F.Fab")
			(hide yes)
			(effects
				(font
					(size 1 1)
					(thickness 0.15)
				)
			)
		)
		(property "Voltage" "50V"
			(at 213.5425 -80.4455 0)
			(layer "F.Fab")
			(hide yes)
			(effects
				(font
					(size 1 1)
					(thickness 0.15)
				)
			)
		)
		(sheetname "/Power/")
		(sheetfile "power.kicad_sch")
		(attr smd)
		(fp_rect
			(start -0.925 -0.47)
			(end 0.925 0.47)
			(stroke
				(width 0.05)
				(type default)
			)
			(fill no)
			(layer "F.CrtYd")
		)
		(fp_line
			(start 0.504 -0.25)
			(end 0.504 0.248)
			(stroke
				(width 0.15)
				(type solid)
			)
			(layer "F.Fab")
		)
		(fp_line
			(start -0.494 -0.25)
			(end 0.504 -0.25)
			(stroke
				(width 0.15)
				(type solid)
			)
			(layer "F.Fab")
		)
		(fp_line
			(start 0.504 0.248)
			(end -0.494 0.248)
			(stroke
				(width 0.15)
				(type solid)
			)
			(layer "F.Fab")
		)
		(fp_line
			(start -0.494 0.248)
			(end -0.494 -0.25)
			(stroke
				(width 0.15)
				(type solid)
			)
			(layer "F.Fab")
		)
		(pad "1" smd roundrect
			(at -0.48 0 90)
			(size 0.59 0.64)
			(layers "F.Cu" "F.Mask" "F.Paste")
			(roundrect_rratio 0.25)
			(net 1 "GND")
			(pintype "passive")
		)
		(pad "2" smd roundrect
			(at 0.48 0 90)
			(size 0.59 0.64)
			(layers "F.Cu" "F.Mask" "F.Paste")
			(roundrect_rratio 0.25)
			(net 4 "+12V")
			(pintype "passive")
		)
	)
	(footprint "antmicro-footprints:R_0402_1005Metric"
		(layer "F.Cu")
		(at 170.688 66.818)
		(descr "Resistor SMD 0402")
		(tags "resistor SMD 0402")
		(property "Reference" "R67"
			(at -3.148968 0.328135 0)
			(layer "F.SilkS")
			(effects
				(font
					(size 0.7 0.7)
					(thickness 0.15)
				)
				(justify left bottom)
			)
		)
		(property "Value" "R_100R_0402"
			(at -1.011843 1.772047 0)
			(layer "F.Fab")
			(effects
				(font
					(size 0.7 0.7)
					(thickness 0.15)
				)
				(justify left bottom)
			)
		)
		(property "Datasheet" "https://www.bourns.com/docs/product-datasheets/cr.pdf"
			(at 0 0 0)
			(layer "F.Fab")
			(hide yes)
			(effects
				(font
					(size 1.27 1.27)
					(thickness 0.15)
				)
			)
		)
		(property "Description" "SMD Chip Resistor, 100 ohm, ± 1%, 62.5 mW, 0402 [1005 Metric], Thick Film, General Purpose"
			(at 0 0 0)
			(layer "F.Fab")
			(hide yes)
			(effects
				(font
					(size 1.27 1.27)
					(thickness 0.15)
				)
			)
		)
		(property "Author" "Antmicro"
			(at 0 0 0)
			(layer "F.Fab")
			(hide yes)
			(effects
				(font
					(size 1 1)
					(thickness 0.15)
				)
			)
		)
		(property "License" "Apache-2.0"
			(at 0 0 0)
			(layer "F.Fab")
			(hide yes)
			(effects
				(font
					(size 1 1)
					(thickness 0.15)
				)
			)
		)
		(property "MPN" "CR0402-FX-1000GLF"
			(at 0 0 0)
			(layer "F.Fab")
			(hide yes)
			(effects
				(font
					(size 1 1)
					(thickness 0.15)
				)
			)
		)
		(property "Manufacturer" "Bourns"
			(at 0 0 0)
			(layer "F.Fab")
			(hide yes)
			(effects
				(font
					(size 1 1)
					(thickness 0.15)
				)
			)
		)
		(property "Tolerance" "1%"
			(at 0 0 0)
			(layer "F.Fab")
			(hide yes)
			(effects
				(font
					(size 1 1)
					(thickness 0.15)
				)
			)
		)
		(property "Val" "100R"
			(at 0 0 0)
			(layer "F.Fab")
			(hide yes)
			(effects
				(font
					(size 1 1)
					(thickness 0.15)
				)
			)
		)
		(sheetname "/Connectors/")
		(sheetfile "connectors.kicad_sch")
		(attr smd)
		(fp_rect
			(start -0.925 -0.47)
			(end 0.925 0.47)
			(stroke
				(width 0.05)
				(type default)
			)
			(fill no)
			(layer "F.CrtYd")
		)
		(fp_rect
			(start -0.5 -0.25)
			(end 0.5 0.25)
			(stroke
				(width 0.15)
				(type solid)
			)
			(fill no)
			(layer "F.Fab")
		)
		(pad "1" smd roundrect
			(at -0.48 0)
			(size 0.59 0.64)
			(layers "F.Cu" "F.Mask" "F.Paste")
			(roundrect_rratio 0.25)
			(net 121 "/Connectors/SCL")
			(pintype "passive")
		)
		(pad "2" smd roundrect
			(at 0.48 0)
			(size 0.59 0.64)
			(layers "F.Cu" "F.Mask" "F.Paste")
			(roundrect_rratio 0.25)
			(net 134 "Net-(U8-A_{2})")
			(pintype "passive")
		)
	)
	(footprint "antmicro-footprints:SOD-523_NP"
		(layer "F.Cu")
		(at 177.038 69.088)
		(property "Reference" "D6"
			(at -2.54 0.508 0)
			(layer "F.SilkS")
			(effects
				(font
					(size 0.7 0.7)
					(thickness 0.15)
				)
				(justify left bottom)
			)
		)
		(property "Value" "ESD5B5_0ST1G"
			(at 0 1.499 0)
			(layer "F.Fab")
			(effects
				(font
					(size 0.7 0.7)
					(thickness 0.15)
				)
				(justify left bottom)
			)
		)
		(property "Datasheet" "https://www.onsemi.com/pdf/datasheet/esd5b5.0st1-d.pdf"
			(at 0 0 0)
			(layer "F.Fab")
			(hide yes)
			(effects
				(font
					(size 1.27 1.27)
					(thickness 0.15)
				)
			)
		)
		(property "Description" "Bidirectional TVS, 30 kV,  SOD-523, 5 V, 32 pF"
			(at 0 0 0)
			(layer "F.Fab")
			(hide yes)
			(effects
				(font
					(size 1.27 1.27)
					(thickness 0.15)
				)
			)
		)
		(property "Author" "Antmicro"
			(at 0 0 0)
			(layer "F.Fab")
			(hide yes)
			(effects
				(font
					(size 1 1)
					(thickness 0.15)
				)
			)
		)
		(property "License" "Apache-2.0"
			(at 0 0 0)
			(layer "F.Fab")
			(hide yes)
			(effects
				(font
					(size 1 1)
					(thickness 0.15)
				)
			)
		)
		(property "MPN" "ESD5B5.0ST1G"
			(at 0 0 0)
			(layer "F.Fab")
			(hide yes)
			(effects
				(font
					(size 1 1)
					(thickness 0.15)
				)
			)
		)
		(property "Manufacturer" "ON Semiconductor"
			(at 0 0 0)
			(layer "F.Fab")
			(hide yes)
			(effects
				(font
					(size 1 1)
					(thickness 0.15)
				)
			)
		)
		(sheetname "/Connectors/")
		(sheetfile "connectors.kicad_sch")
		(attr smd)
		(fp_rect
			(start -1 -0.6)
			(end 1 0.6)
			(stroke
				(width 0.05)
				(type solid)
			)
			(fill no)
			(layer "F.CrtYd")
		)
		(fp_line
			(start -0.652 -0.425)
			(end 0.65 -0.425)
			(stroke
				(width 0.15)
				(type solid)
			)
			(layer "F.Fab")
		)
		(fp_line
			(start -0.652 0.423)
			(end -0.652 -0.425)
			(stroke
				(width 0.15)
				(type solid)
			)
			(layer "F.Fab")
		)
		(fp_line
			(start -0.652 0.423)
			(end 0.65 0.423)
			(stroke
				(width 0.15)
				(type solid)
			)
			(layer "F.Fab")
		)
		(fp_line
			(start 0.65 -0.425)
			(end 0.65 0.423)
			(stroke
				(width 0.15)
				(type solid)
			)
			(layer "F.Fab")
		)
		(pad "1" smd roundrect
			(at -0.701 0)
			(size 0.5 0.6)
			(layers "F.Cu" "F.Mask" "F.Paste")
			(roundrect_rratio 0.25)
			(net 1 "GND")
			(pinfunction "C")
			(pintype "passive")
		)
		(pad "2" smd roundrect
			(at 0.699 0)
			(size 0.5 0.6)
			(layers "F.Cu" "F.Mask" "F.Paste")
			(roundrect_rratio 0.25)
			(net 67 "/Connectors/VSYNC_CAM0")
			(pinfunction "A")
			(pintype "passive")
		)
	)
	(footprint "antmicro-footprints:R_0402_1005Metric"
		(layer "F.Cu")
		(at 181.356 69.192)
		(descr "Resistor SMD 0402")
		(tags "resistor SMD 0402")
		(property "Reference" "R9"
			(at -1.279 9.1162 0)
			(layer "F.SilkS")
			(effects
				(font
					(size 0.7 0.7)
					(thickness 0.15)
				)
				(justify left bottom)
			)
		)
		(property "Value" "R_100R_0402"
			(at -1.011843 1.772047 0)
			(layer "F.Fab")
			(effects
				(font
					(size 0.7 0.7)
					(thickness 0.15)
				)
				(justify left bottom)
			)
		)
		(property "Datasheet" "https://www.bourns.com/docs/product-datasheets/cr.pdf"
			(at 0 0 0)
			(layer "F.Fab")
			(hide yes)
			(effects
				(font
					(size 1.27 1.27)
					(thickness 0.15)
				)
			)
		)
		(property "Description" "SMD Chip Resistor, 100 ohm, ± 1%, 62.5 mW, 0402 [1005 Metric], Thick Film, General Purpose"
			(at 0 0 0)
			(layer "F.Fab")
			(hide yes)
			(effects
				(font
					(size 1.27 1.27)
					(thickness 0.15)
				)
			)
		)
		(property "Author" "Antmicro"
			(at 0 0 0)
			(layer "F.Fab")
			(hide yes)
			(effects
				(font
					(size 1 1)
					(thickness 0.15)
				)
			)
		)
		(property "License" "Apache-2.0"
			(at 0 0 0)
			(layer "F.Fab")
			(hide yes)
			(effects
				(font
					(size 1 1)
					(thickness 0.15)
				)
			)
		)
		(property "MPN" "CR0402-FX-1000GLF"
			(at 0 0 0)
			(layer "F.Fab")
			(hide yes)
			(effects
				(font
					(size 1 1)
					(thickness 0.15)
				)
			)
		)
		(property "Manufacturer" "Bourns"
			(at 0 0 0)
			(layer "F.Fab")
			(hide yes)
			(effects
				(font
					(size 1 1)
					(thickness 0.15)
				)
			)
		)
		(property "Tolerance" "1%"
			(at 0 0 0)
			(layer "F.Fab")
			(hide yes)
			(effects
				(font
					(size 1 1)
					(thickness 0.15)
				)
			)
		)
		(property "Val" "100R"
			(at 0 0 0)
			(layer "F.Fab")
			(hide yes)
			(effects
				(font
					(size 1 1)
					(thickness 0.15)
				)
			)
		)
		(sheetname "/Connectors/")
		(sheetfile "connectors.kicad_sch")
		(attr smd)
		(fp_rect
			(start -0.925 -0.47)
			(end 0.925 0.47)
			(stroke
				(width 0.05)
				(type default)
			)
			(fill no)
			(layer "F.CrtYd")
		)
		(fp_rect
			(start -0.5 -0.25)
			(end 0.5 0.25)
			(stroke
				(width 0.15)
				(type solid)
			)
			(fill no)
			(layer "F.Fab")
		)
		(pad "1" smd roundrect
			(at -0.48 0)
			(size 0.59 0.64)
			(layers "F.Cu" "F.Mask" "F.Paste")
			(roundrect_rratio 0.25)
			(net 67 "/Connectors/VSYNC_CAM0")
			(pintype "passive")
		)
		(pad "2" smd roundrect
			(at 0.48 0)
			(size 0.59 0.64)
			(layers "F.Cu" "F.Mask" "F.Paste")
			(roundrect_rratio 0.25)
			(net 35 "Net-(J6-Pad32)")
			(pintype "passive")
		)
	)
	(footprint "antmicro-footprints:TP_SMD_0.75mm"
		(layer "F.Cu")
		(at 153.924 97.89)
		(property "Reference" "TP9"
			(at 0 -0.6 0)
			(layer "F.SilkS")
			(hide yes)
			(effects
				(font
					(size 0.7 0.7)
					(thickness 0.15)
				)
				(justify left bottom)
			)
		)
		(property "Value" "TP_0.75mm_SMD"
			(at 0 1.2 0)
			(layer "F.Fab")
			(effects
				(font
					(size 0.7 0.7)
					(thickness 0.15)
				)
				(justify left bottom)
			)
		)
		(property "Description" "SMT test point"
			(at 0 0 0)
			(layer "F.Fab")
			(hide yes)
			(effects
				(font
					(size 1.27 1.27)
					(thickness 0.15)
				)
			)
		)
		(property "Author" "Antmicro"
			(at 0 0 0)
			(layer "F.Fab")
			(hide yes)
			(effects
				(font
					(size 1 1)
					(thickness 0.15)
				)
			)
		)
		(property "License" "Apache-2.0"
			(at 0 0 0)
			(layer "F.Fab")
			(hide yes)
			(effects
				(font
					(size 1 1)
					(thickness 0.15)
				)
			)
		)
		(property "MPN" ""
			(at 0 0 0)
			(layer "F.Fab")
			(hide yes)
			(effects
				(font
					(size 1 1)
					(thickness 0.15)
				)
			)
		)
		(property "Manufacturer" ""
			(at 0 0 0)
			(layer "F.Fab")
			(hide yes)
			(effects
				(font
					(size 1 1)
					(thickness 0.15)
				)
			)
		)
		(sheetname "/Power/")
		(sheetfile "power.kicad_sch")
		(fp_circle
			(center 0 0)
			(end 0.475 0)
			(stroke
				(width 0.05)
				(type default)
			)
			(fill no)
			(layer "F.CrtYd")
		)
		(pad "1" smd circle
			(at 0 0)
			(size 0.75 0.75)
			(layers "F.Cu" "F.Mask")
			(net 118 "/Connectors/DC_IN")
			(pinfunction "1")
			(pintype "passive")
		)
	)
)
